# TIMECARD (Time Appliance Project (Time Card)) — schematic netlist excerpt (pin names and nets, part order shuffled) for the footprints in the layout excerpt that follows; sources: Cadence DE-HDL packaged netlist, KiCad conversion of R4006-B0001-02_R01.brd

DS19  OPTICAL  pkg SMC_DS_063X031_V4  page 26 : A = UNNAMED_14_OPTICAL_I191_A ; C = SG
SP50  NULL  pkg DUMMY  page 34

(kicad_pcb
	(version 20260206)
	(generator "pcbnew")
	(generator_version "10.0")
	(general
		(thickness 1.6)
		(legacy_teardrops no)
	)
	(paper "A4")
	(title_block
		(title "timecard-production-celestica-r4006 — R4006-B0001-02_R01.brd")
		(comment 1 "Time Appliance Project (Time Card) / footprints 334-335 of 1113")
	)
	(layers
		(0 "F.Cu" signal "TOP")
		(4 "In1.Cu" signal "L02_GND1")
		(6 "In2.Cu" signal "L03_SIG1")
		(8 "In3.Cu" signal "L04_GND2")
		(10 "In4.Cu" signal "L05_VCC1")
		(12 "In5.Cu" signal "L06_VCC2")
		(14 "In6.Cu" signal "L07_GND3")
		(16 "In7.Cu" signal "L08_SIG2")
		(18 "In8.Cu" signal "L09_GND4")
		(2 "B.Cu" signal "BOTTOM")
		(9 "F.Adhes" user "F.Adhesive")
		(11 "B.Adhes" user "B.Adhesive")
		(13 "F.Paste" user "Package Geometry/Pastemask Top")
		(15 "B.Paste" user "Package Geometry/Pastemask Bottom")
		(5 "F.SilkS" user "Ref Des/Silkscreen Top")
		(7 "B.SilkS" user "Ref Des/Silkscreen Bottom")
		(1 "F.Mask" user "Board Geometry/Soldermask Top")
		(3 "B.Mask" user "Board Geometry/Soldermask Bottom")
		(17 "Dwgs.User" user "User.Drawings")
		(19 "Cmts.User" user "User.Comments")
		(21 "Eco1.User" user "User.Eco1")
		(23 "Eco2.User" user "User.Eco2")
		(25 "Edge.Cuts" user "Board Geometry/Outline")
		(27 "Margin" user)
		(31 "F.CrtYd" user "Package Geometry/Place Bound Top")
		(29 "B.CrtYd" user "Package Geometry/Place Bound Bottom")
		(35 "F.Fab" user "Ref Des/Assembly Top")
		(33 "B.Fab" user "Ref Des/Assembly Bottom")
	)
	(footprint ""
		(layer "F.Cu")
		(at 150.049992 -104.350058 -90)
		(property "Reference" "DS19"
			(at 0.845058 -1.424178 90)
			(unlocked yes)
			(layer "F.SilkS")
			(effects
				(font
					(size 0.7874 0.5842)
					(thickness 0.1524)
				)
			)
		)
		(property "Value" ""
			(at 0 0 270)
			(layer "F.Fab")
			(effects
				(font
					(size 1.27 1.27)
				)
			)
		)
		(property "Device Type" "OPTICAL-G170-10143-01"
			(at 0.1778 1.483081 270)
			(unlocked yes)
			(layer "F.Fab")
			(hide yes)
			(effects
				(font
					(size 0.786892 0.583946)
					(thickness 0.000001)
				)
			)
		)
		(property "User Part Number" "PARTNUM*"
			(at 0.1778 2.422881 270)
			(unlocked yes)
			(layer "Cmts.User")
			(hide yes)
			(effects
				(font
					(size 0.786892 0.583946)
					(thickness 0.000001)
				)
			)
		)
		(duplicate_pad_numbers_are_jumpers no)
		(fp_line
			(start -1.397508 0.704088)
			(end -1.397508 -0.704088)
			(stroke
				(width 0.1)
				(type default)
			)
			(layer "F.SilkS")
		)
		(fp_line
			(start 1.397508 0.704088)
			(end -1.397508 0.704088)
			(stroke
				(width 0.1)
				(type default)
			)
			(layer "F.SilkS")
		)
		(fp_line
			(start -2.3368 0.0762)
			(end -3.6068 0.0762)
			(stroke
				(width 0.1)
				(type default)
			)
			(layer "F.SilkS")
		)
		(fp_line
			(start -2.9718 -0.5588)
			(end -2.9718 0.7112)
			(stroke
				(width 0.1)
				(type default)
			)
			(layer "F.SilkS")
		)
		(fp_line
			(start -1.397508 -0.704088)
			(end 1.397508 -0.704088)
			(stroke
				(width 0.1)
				(type default)
			)
			(layer "F.SilkS")
		)
		(fp_line
			(start 1.397508 -0.704088)
			(end 1.397508 0.704088)
			(stroke
				(width 0.1)
				(type default)
			)
			(layer "F.SilkS")
		)
		(fp_poly
			(pts
				(xy 1.397508 0.704088) (xy 1.397508 -0.704088) (xy 1.905508 -0.704088) (xy 1.905508 0.704088)
			)
			(stroke
				(width 0)
				(type default)
			)
			(fill yes)
			(layer "F.SilkS")
		)
		(fp_poly
			(pts
				(xy -1.651508 0.958088) (xy 1.905508 0.958088) (xy 1.905508 -0.958088) (xy -1.651508 -0.958088)
			)
			(stroke
				(width 0)
				(type default)
			)
			(fill no)
			(layer "F.CrtYd")
		)
		(fp_line
			(start -0.850138 0.450088)
			(end 0.850138 0.450088)
			(stroke
				(width 0.1)
				(type default)
			)
			(layer "F.Fab")
		)
		(fp_line
			(start 0.850138 0.450088)
			(end 0.850138 -0.450088)
			(stroke
				(width 0.1)
				(type default)
			)
			(layer "F.Fab")
		)
		(fp_line
			(start -2.4638 0.0762)
			(end -3.7338 0.0762)
			(stroke
				(width 0.1)
				(type default)
			)
			(layer "F.Fab")
		)
		(fp_line
			(start -0.850138 -0.450088)
			(end -0.850138 0.450088)
			(stroke
				(width 0.1)
				(type default)
			)
			(layer "F.Fab")
		)
		(fp_line
			(start 0.850138 -0.450088)
			(end -0.850138 -0.450088)
			(stroke
				(width 0.1)
				(type default)
			)
			(layer "F.Fab")
		)
		(fp_line
			(start -3.0988 -0.5588)
			(end -3.0988 0.7112)
			(stroke
				(width 0.1)
				(type default)
			)
			(layer "F.Fab")
		)
		(fp_poly
			(pts
				(xy 0.850138 -0.450088) (xy 0.850138 0.450088) (xy 0.342138 0.450088) (xy 0.342138 -0.450088)
			)
			(stroke
				(width 0)
				(type default)
			)
			(fill yes)
			(layer "F.Fab")
		)
		(fp_text user "A"
			(at -2.044192 0.697992 0)
			(unlocked yes)
			(layer "F.SilkS")
			(effects
				(font
					(size 0.635 0.4064)
					(thickness 0.1524)
				)
			)
		)
		(fp_text user "C"
			(at 2.527808 0.189992 0)
			(unlocked yes)
			(layer "F.SilkS")
			(effects
				(font
					(size 0.635 0.4064)
					(thickness 0.1524)
				)
			)
		)
		(fp_text user "A"
			(at -1.9558 0.142748 90)
			(unlocked yes)
			(layer "F.Fab")
			(effects
				(font
					(size 0.7874 0.5842)
					(thickness 0.1524)
				)
			)
		)
		(fp_text user "C"
			(at 1.900428 -0.826008 0)
			(unlocked yes)
			(layer "F.Fab")
			(effects
				(font
					(size 0.7874 0.5842)
					(thickness 0.1524)
				)
			)
		)
		(pad "A" smd rect
			(at -0.749808 0 270)
			(size 0.7874 0.7874)
			(layers "F.Cu" "F.Mask" "F.Paste")
			(net "UNNAMED_14_OPTICAL_I191_A")
		)
		(pad "C" smd rect
			(at 0.749808 0 270)
			(size 0.7874 0.7874)
			(layers "F.Cu" "F.Mask" "F.Paste")
			(net "SG")
		)
	)
	(footprint ""
		(layer "F.Cu")
		(at 56.007 -127.635)
		(property "Reference" "SP50"
			(at 0 0 0)
			(layer "F.SilkS")
			(hide yes)
			(effects
				(font
					(size 1.27 1.27)
				)
			)
		)
		(property "Value" ""
			(at 0 0 0)
			(layer "F.Fab")
			(effects
				(font
					(size 1.27 1.27)
				)
			)
		)
		(duplicate_pad_numbers_are_jumpers no)
	)
)
